FILE_TYPE=LIBRARY_PARTS;
primitive 'SCONN168_ME1016810202011';
  pin
    'NIC_PWR_GOOD':
      PIN_NUMBER='(OB1)';
      INPUT_LOAD='(-0.01,0.01)';
    'MAIN_PWR_EN':
      PIN_NUMBER='(OB2)';
      OUTPUT_LOAD='(1.0,-1.0)';
    'LD#':
      PIN_NUMBER='(OB3)';
      OUTPUT_LOAD='(1.0,-1.0)';
    'DATA_IN':
      PIN_NUMBER='(OB4)';
      INPUT_LOAD='(-0.01,0.01)';
    'DATA_OUT':
      PIN_NUMBER='(OB5)';
      OUTPUT_LOAD='(1.0,-1.0)';
    'CLK':
      PIN_NUMBER='(OB6)';
      OUTPUT_LOAD='(1.0,-1.0)';
    'SLOT_ID0':
      PIN_NUMBER='(OB7)';
      OUTPUT_LOAD='(1.0,-1.0)';
    'RBT_RXD1':
      PIN_NUMBER='(OB8)';
      INPUT_LOAD='(-0.01,0.01)';
    'RBT_RXD0':
      PIN_NUMBER='(OB9)';
      INPUT_LOAD='(-0.01,0.01)';
    'GND_OB10':
      PIN_NUMBER='(OB10)';
      PINUSE='POWER';
      NO_LOAD_CHECK='Both';
      NO_IO_CHECK='Both';
      NO_ASSERT_CHECK='TRUE';
      NO_DIR_CHECK='TRUE';
      ALLOW_CONNECT='TRUE';
    'REFCLKN2':
      PIN_NUMBER='(OB11)';
      OUTPUT_LOAD='(1.0,-1.0)';
    'REFCLKP2':
      PIN_NUMBER='(OB12)';
      OUTPUT_LOAD='(1.0,-1.0)';
    'GND_OB13':
      PIN_NUMBER='(OB13)';
      PINUSE='POWER';
      NO_LOAD_CHECK='Both';
      NO_IO_CHECK='Both';
      NO_ASSERT_CHECK='TRUE';
      NO_DIR_CHECK='TRUE';
      ALLOW_CONNECT='TRUE';
    'RBT_CRS_DV':
      PIN_NUMBER='(OB14)';
      OUTPUT_LOAD='(1.0,-1.0)';
    '+12V_EDGE_B1':
      PIN_NUMBER='(B1)';
      PINUSE='POWER';
      NO_LOAD_CHECK='Both';
      NO_IO_CHECK='Both';
      NO_ASSERT_CHECK='TRUE';
      NO_DIR_CHECK='TRUE';
      ALLOW_CONNECT='TRUE';
    '+12V_EDGE_B2':
      PIN_NUMBER='(B2)';
      PINUSE='POWER';
      NO_LOAD_CHECK='Both';
      NO_IO_CHECK='Both';
      NO_ASSERT_CHECK='TRUE';
      NO_DIR_CHECK='TRUE';
      ALLOW_CONNECT='TRUE';
    '+12V_EDGE_B3':
      PIN_NUMBER='(B3)';
      PINUSE='POWER';
      NO_LOAD_CHECK='Both';
      NO_IO_CHECK='Both';
      NO_ASSERT_CHECK='TRUE';
      NO_DIR_CHECK='TRUE';
      ALLOW_CONNECT='TRUE';
    '+12V_EDGE_B4':
      PIN_NUMBER='(B4)';
      PINUSE='POWER';
      NO_LOAD_CHECK='Both';
      NO_IO_CHECK='Both';
      NO_ASSERT_CHECK='TRUE';
      NO_DIR_CHECK='TRUE';
      ALLOW_CONNECT='TRUE';
    '+12V_EDGE_B5':
      PIN_NUMBER='(B5)';
      PINUSE='POWER';
      NO_LOAD_CHECK='Both';
      NO_IO_CHECK='Both';
      NO_ASSERT_CHECK='TRUE';
      NO_DIR_CHECK='TRUE';
      ALLOW_CONNECT='TRUE';
    '+12V_EDGE_B6':
      PIN_NUMBER='(B6)';
      PINUSE='POWER';
      NO_LOAD_CHECK='Both';
      NO_IO_CHECK='Both';
      NO_ASSERT_CHECK='TRUE';
      NO_DIR_CHECK='TRUE';
      ALLOW_CONNECT='TRUE';
    'BIF0#':
      PIN_NUMBER='(B7)';
      OUTPUT_LOAD='(1.0,-1.0)';
    'BIF1#':
      PIN_NUMBER='(B8)';
      OUTPUT_LOAD='(1.0,-1.0)';
    'BIF2#':
      PIN_NUMBER='(B9)';
      OUTPUT_LOAD='(1.0,-1.0)';
    'PERST0#':
      PIN_NUMBER='(B10)';
      OUTPUT_LOAD='(1.0,-1.0)';
    '+3.3V_EDGE':
      PIN_NUMBER='(B11)';
      PINUSE='POWER';
      NO_LOAD_CHECK='Both';
      NO_IO_CHECK='Both';
      NO_ASSERT_CHECK='TRUE';
      NO_DIR_CHECK='TRUE';
      ALLOW_CONNECT='TRUE';
    'AUX_PWR_EN':
      PIN_NUMBER='(B12)';
      OUTPUT_LOAD='(1.0,-1.0)';
    'GND_B13':
      PIN_NUMBER='(B13)';
      PINUSE='POWER';
      NO_LOAD_CHECK='Both';
      NO_IO_CHECK='Both';
      NO_ASSERT_CHECK='TRUE';
      NO_DIR_CHECK='TRUE';
      ALLOW_CONNECT='TRUE';
    'REFCLKN0':
      PIN_NUMBER='(B14)';
      INPUT_LOAD='(-0.01,0.01)';
    'REFCLKP0':
      PIN_NUMBER='(B15)';
      OUTPUT_LOAD='(1.0,-1.0)';
    'GND_B16':
      PIN_NUMBER='(B16)';
      PINUSE='POWER';
      NO_LOAD_CHECK='Both';
      NO_IO_CHECK='Both';
      NO_ASSERT_CHECK='TRUE';
      NO_DIR_CHECK='TRUE';
      ALLOW_CONNECT='TRUE';
    'PETN0':
      PIN_NUMBER='(B17)';
      OUTPUT_LOAD='(1.0,-1.0)';
    'PETP0':
      PIN_NUMBER='(B18)';
      OUTPUT_LOAD='(1.0,-1.0)';
    'GND_B19':
      PIN_NUMBER='(B19)';
      PINUSE='POWER';
      NO_LOAD_CHECK='Both';
      NO_IO_CHECK='Both';
      NO_ASSERT_CHECK='TRUE';
      NO_DIR_CHECK='TRUE';
      ALLOW_CONNECT='TRUE';
    'PETN1':
      PIN_NUMBER='(B20)';
      OUTPUT_LOAD='(1.0,-1.0)';
    'PETP1':
      PIN_NUMBER='(B21)';
      OUTPUT_LOAD='(1.0,-1.0)';
    'GND_B22':
      PIN_NUMBER='(B22)';
      PINUSE='POWER';
      NO_LOAD_CHECK='Both';
      NO_IO_CHECK='Both';
      NO_ASSERT_CHECK='TRUE';
      NO_DIR_CHECK='TRUE';
      ALLOW_CONNECT='TRUE';
    'PETN2':
      PIN_NUMBER='(B23)';
      OUTPUT_LOAD='(1.0,-1.0)';
    'PETP2':
      PIN_NUMBER='(B24)';
      OUTPUT_LOAD='(1.0,-1.0)';
    'GND_B25':
      PIN_NUMBER='(B25)';
      PINUSE='POWER';
      NO_LOAD_CHECK='Both';
      NO_IO_CHECK='Both';
      NO_ASSERT_CHECK='TRUE';
      NO_DIR_CHECK='TRUE';
      ALLOW_CONNECT='TRUE';
    'PETN3':
      PIN_NUMBER='(B26)';
      OUTPUT_LOAD='(1.0,-1.0)';
    'PETP3':
      PIN_NUMBER='(B27)';
      OUTPUT_LOAD='(1.0,-1.0)';
    'GND_B28':
      PIN_NUMBER='(B28)';
      PINUSE='POWER';
      NO_LOAD_CHECK='Both';
      NO_IO_CHECK='Both';
      NO_ASSERT_CHECK='TRUE';
      NO_DIR_CHECK='TRUE';
      ALLOW_CONNECT='TRUE';
    'GND_B29':
      PIN_NUMBER='(B29)';
      PINUSE='POWER';
      NO_LOAD_CHECK='Both';
      NO_IO_CHECK='Both';
      NO_ASSERT_CHECK='TRUE';
      NO_DIR_CHECK='TRUE';
      ALLOW_CONNECT='TRUE';
    'PETN4':
      PIN_NUMBER='(B30)';
      OUTPUT_LOAD='(1.0,-1.0)';
    'PETP4':
      PIN_NUMBER='(B31)';
      OUTPUT_LOAD='(1.0,-1.0)';
    'GND_B32':
      PIN_NUMBER='(B32)';
      PINUSE='POWER';
      NO_LOAD_CHECK='Both';
      NO_IO_CHECK='Both';
      NO_ASSERT_CHECK='TRUE';
      NO_DIR_CHECK='TRUE';
      ALLOW_CONNECT='TRUE';
    'PETN5':
      PIN_NUMBER='(B33)';
      OUTPUT_LOAD='(1.0,-1.0)';
    'PETP5':
      PIN_NUMBER='(B34)';
      OUTPUT_LOAD='(1.0,-1.0)';
    'GND_B35':
      PIN_NUMBER='(B35)';
      PINUSE='POWER';
      NO_LOAD_CHECK='Both';
      NO_IO_CHECK='Both';
      NO_ASSERT_CHECK='TRUE';
      NO_DIR_CHECK='TRUE';
      ALLOW_CONNECT='TRUE';
    'PETN6':
      PIN_NUMBER='(B36)';
      OUTPUT_LOAD='(1.0,-1.0)';
    'PETP6':
      PIN_NUMBER='(B37)';
      OUTPUT_LOAD='(1.0,-1.0)';
    'GND_B38':
      PIN_NUMBER='(B38)';
      PINUSE='POWER';
      NO_LOAD_CHECK='Both';
      NO_IO_CHECK='Both';
      NO_ASSERT_CHECK='TRUE';
      NO_DIR_CHECK='TRUE';
      ALLOW_CONNECT='TRUE';
    'PETN7':
      PIN_NUMBER='(B39)';
      OUTPUT_LOAD='(1.0,-1.0)';
    'PETP7':
      PIN_NUMBER='(B40)';
      OUTPUT_LOAD='(1.0,-1.0)';
    'GND_B41':
      PIN_NUMBER='(B41)';
      PINUSE='POWER';
      NO_LOAD_CHECK='Both';
      NO_IO_CHECK='Both';
      NO_ASSERT_CHECK='TRUE';
      NO_DIR_CHECK='TRUE';
      ALLOW_CONNECT='TRUE';
    'PRSNTB0#':
      PIN_NUMBER='(B42)';
      INPUT_LOAD='(-0.01,0.01)';
    'GND_B43':
      PIN_NUMBER='(B43)';
      PINUSE='POWER';
      NO_LOAD_CHECK='Both';
      NO_IO_CHECK='Both';
      NO_ASSERT_CHECK='TRUE';
      NO_DIR_CHECK='TRUE';
      ALLOW_CONNECT='TRUE';
    'PETN8':
      PIN_NUMBER='(B44)';
      OUTPUT_LOAD='(1.0,-1.0)';
    'PETP8':
      PIN_NUMBER='(B45)';
      OUTPUT_LOAD='(1.0,-1.0)';
    'GND_B46':
      PIN_NUMBER='(B46)';
      PINUSE='POWER';
      NO_LOAD_CHECK='Both';
      NO_IO_CHECK='Both';
      NO_ASSERT_CHECK='TRUE';
      NO_DIR_CHECK='TRUE';
      ALLOW_CONNECT='TRUE';
    'PETN9':
      PIN_NUMBER='(B47)';
      OUTPUT_LOAD='(1.0,-1.0)';
    'PETP9':
      PIN_NUMBER='(B48)';
      OUTPUT_LOAD='(1.0,-1.0)';
    'GND_B49':
      PIN_NUMBER='(B49)';
      PINUSE='POWER';
      NO_LOAD_CHECK='Both';
      NO_IO_CHECK='Both';
      NO_ASSERT_CHECK='TRUE';
      NO_DIR_CHECK='TRUE';
      ALLOW_CONNECT='TRUE';
    'PETN10':
      PIN_NUMBER='(B50)';
      OUTPUT_LOAD='(1.0,-1.0)';
    'PETP10':
      PIN_NUMBER='(B51)';
      OUTPUT_LOAD='(1.0,-1.0)';
    'GND_B52':
      PIN_NUMBER='(B52)';
      PINUSE='POWER';
      NO_LOAD_CHECK='Both';
      NO_IO_CHECK='Both';
      NO_ASSERT_CHECK='TRUE';
      NO_DIR_CHECK='TRUE';
      ALLOW_CONNECT='TRUE';
    'PETN11':
      PIN_NUMBER='(B53)';
      OUTPUT_LOAD='(1.0,-1.0)';
    'PETP11':
      PIN_NUMBER='(B54)';
      OUTPUT_LOAD='(1.0,-1.0)';
    'GND_B55':
      PIN_NUMBER='(B55)';
      PINUSE='POWER';
      NO_LOAD_CHECK='Both';
      NO_IO_CHECK='Both';
      NO_ASSERT_CHECK='TRUE';
      NO_DIR_CHECK='TRUE';
      ALLOW_CONNECT='TRUE';
    'PETN12':
      PIN_NUMBER='(B56)';
      OUTPUT_LOAD='(1.0,-1.0)';
    'PERST2#':
      PIN_NUMBER='(OA1)';
      OUTPUT_LOAD='(1.0,-1.0)';
    'PERST3#':
      PIN_NUMBER='(OA2)';
      OUTPUT_LOAD='(1.0,-1.0)';
    'WAKE#':
      PIN_NUMBER='(OA3)';
      INPUT_LOAD='(-0.01,0.01)';
    'RBT_ARB_IN':
      PIN_NUMBER='(OA4)';
      INPUT_LOAD='(-0.01,0.01)';
    'RBT_ARB_OUT':
      PIN_NUMBER='(OA5)';
      OUTPUT_LOAD='(1.0,-1.0)';
    'SLOT_ID1':
      PIN_NUMBER='(OA6)';
      OUTPUT_LOAD='(1.0,-1.0)';
    'RBT_TX_EN':
      PIN_NUMBER='(OA7)';
      OUTPUT_LOAD='(1.0,-1.0)';
    'RBT_TXD1':
      PIN_NUMBER='(OA8)';
      OUTPUT_LOAD='(1.0,-1.0)';
    'RBT_TXD0':
      PIN_NUMBER='(OA9)';
      OUTPUT_LOAD='(1.0,-1.0)';
    'GND_OA10':
      PIN_NUMBER='(OA10)';
      PINUSE='POWER';
      NO_LOAD_CHECK='Both';
      NO_IO_CHECK='Both';
      NO_ASSERT_CHECK='TRUE';
      NO_DIR_CHECK='TRUE';
      ALLOW_CONNECT='TRUE';
    'REFCLKN3':
      PIN_NUMBER='(OA11)';
      OUTPUT_LOAD='(1.0,-1.0)';
    'REFCLKP3':
      PIN_NUMBER='(OA12)';
      OUTPUT_LOAD='(1.0,-1.0)';
    'GND_OA13':
      PIN_NUMBER='(OA13)';
      PINUSE='POWER';
      NO_LOAD_CHECK='Both';
      NO_IO_CHECK='Both';
      NO_ASSERT_CHECK='TRUE';
      NO_DIR_CHECK='TRUE';
      ALLOW_CONNECT='TRUE';
    'RBT_CLK_IN':
      PIN_NUMBER='(OA14)';
      OUTPUT_LOAD='(1.0,-1.0)';
    'GND_A1':
      PIN_NUMBER='(A1)';
      PINUSE='POWER';
      NO_LOAD_CHECK='Both';
      NO_IO_CHECK='Both';
      NO_ASSERT_CHECK='TRUE';
      NO_DIR_CHECK='TRUE';
      ALLOW_CONNECT='TRUE';
    'GND_A2':
      PIN_NUMBER='(A2)';
      PINUSE='POWER';
      NO_LOAD_CHECK='Both';
      NO_IO_CHECK='Both';
      NO_ASSERT_CHECK='TRUE';
      NO_DIR_CHECK='TRUE';
      ALLOW_CONNECT='TRUE';
    'GND_A3':
      PIN_NUMBER='(A3)';
      PINUSE='POWER';
      NO_LOAD_CHECK='Both';
      NO_IO_CHECK='Both';
      NO_ASSERT_CHECK='TRUE';
      NO_DIR_CHECK='TRUE';
      ALLOW_CONNECT='TRUE';
    'GND_A4':
      PIN_NUMBER='(A4)';
      PINUSE='POWER';
      NO_LOAD_CHECK='Both';
      NO_IO_CHECK='Both';
      NO_ASSERT_CHECK='TRUE';
      NO_DIR_CHECK='TRUE';
      ALLOW_CONNECT='TRUE';
    'GND_A5':
      PIN_NUMBER='(A5)';
      PINUSE='POWER';
      NO_LOAD_CHECK='Both';
      NO_IO_CHECK='Both';
      NO_ASSERT_CHECK='TRUE';
      NO_DIR_CHECK='TRUE';
      ALLOW_CONNECT='TRUE';
    'GND_A6':
      PIN_NUMBER='(A6)';
      PINUSE='POWER';
      NO_LOAD_CHECK='Both';
      NO_IO_CHECK='Both';
      NO_ASSERT_CHECK='TRUE';
      NO_DIR_CHECK='TRUE';
      ALLOW_CONNECT='TRUE';
    'SMCLK':
      PIN_NUMBER='(A7)';
      OUTPUT_LOAD='(1.0,-1.0)';
    'SMDAT':
      PIN_NUMBER='(A8)';
      BIDIRECTIONAL='TRUE';
      INPUT_LOAD='(-0.01,0.01)';
      OUTPUT_LOAD='(1.0,-1.0)';
    'SMRST#':
      PIN_NUMBER='(A9)';
      OUTPUT_LOAD='(1.0,-1.0)';
    'PRSNTA#':
      PIN_NUMBER='(A10)';
      OUTPUT_LOAD='(1.0,-1.0)';
    'PERST1#':
      PIN_NUMBER='(A11)';
      OUTPUT_LOAD='(1.0,-1.0)';
    'PRSNTB2#':
      PIN_NUMBER='(A12)';
      INPUT_LOAD='(-0.01,0.01)';
    'GND_A13':
      PIN_NUMBER='(A13)';
      PINUSE='POWER';
      NO_LOAD_CHECK='Both';
      NO_IO_CHECK='Both';
      NO_ASSERT_CHECK='TRUE';
      NO_DIR_CHECK='TRUE';
      ALLOW_CONNECT='TRUE';
    'REFCLKN1':
      PIN_NUMBER='(A14)';
      OUTPUT_LOAD='(1.0,-1.0)';
    'REFCLKP1':
      PIN_NUMBER='(A15)';
      OUTPUT_LOAD='(1.0,-1.0)';
    'GND_A16':
      PIN_NUMBER='(A16)';
      PINUSE='POWER';
      NO_LOAD_CHECK='Both';
      NO_IO_CHECK='Both';
      NO_ASSERT_CHECK='TRUE';
      NO_DIR_CHECK='TRUE';
      ALLOW_CONNECT='TRUE';
    'PERN0':
      PIN_NUMBER='(A17)';
      INPUT_LOAD='(-0.01,0.01)';
    'PERP0':
      PIN_NUMBER='(A18)';
      INPUT_LOAD='(-0.01,0.01)';
    'GND_A19':
      PIN_NUMBER='(A19)';
      PINUSE='POWER';
      NO_LOAD_CHECK='Both';
      NO_IO_CHECK='Both';
      NO_ASSERT_CHECK='TRUE';
      NO_DIR_CHECK='TRUE';
      ALLOW_CONNECT='TRUE';
    'PERN1':
      PIN_NUMBER='(A20)';
      INPUT_LOAD='(-0.01,0.01)';
    'PERP1':
      PIN_NUMBER='(A21)';
      INPUT_LOAD='(-0.01,0.01)';
    'GND_A22':
      PIN_NUMBER='(A22)';
      PINUSE='POWER';
      NO_LOAD_CHECK='Both';
      NO_IO_CHECK='Both';
      NO_ASSERT_CHECK='TRUE';
      NO_DIR_CHECK='TRUE';
      ALLOW_CONNECT='TRUE';
    'PERN2':
      PIN_NUMBER='(A23)';
      INPUT_LOAD='(-0.01,0.01)';
    'PERP2':
      PIN_NUMBER='(A24)';
      INPUT_LOAD='(-0.01,0.01)';
    'GND_A25':
      PIN_NUMBER='(A25)';
      PINUSE='POWER';
      NO_LOAD_CHECK='Both';
      NO_IO_CHECK='Both';
      NO_ASSERT_CHECK='TRUE';
      NO_DIR_CHECK='TRUE';
      ALLOW_CONNECT='TRUE';
    'PERN3':
      PIN_NUMBER='(A26)';
      INPUT_LOAD='(-0.01,0.01)';
    'PERP3':
      PIN_NUMBER='(A27)';
      INPUT_LOAD='(-0.01,0.01)';
    'GND_A28':
      PIN_NUMBER='(A28)';
      PINUSE='POWER';
      NO_LOAD_CHECK='Both';
      NO_IO_CHECK='Both';
      NO_ASSERT_CHECK='TRUE';
      NO_DIR_CHECK='TRUE';
      ALLOW_CONNECT='TRUE';
    'GND_A29':
      PIN_NUMBER='(A29)';
      PINUSE='POWER';
      NO_LOAD_CHECK='Both';
      NO_IO_CHECK='Both';
      NO_ASSERT_CHECK='TRUE';
      NO_DIR_CHECK='TRUE';
      ALLOW_CONNECT='TRUE';
    'PERN4':
      PIN_NUMBER='(A30)';
      INPUT_LOAD='(-0.01,0.01)';
    'PERP4':
      PIN_NUMBER='(A31)';
      INPUT_LOAD='(-0.01,0.01)';
    'GND_A32':
      PIN_NUMBER='(A32)';
      PINUSE='POWER';
      NO_LOAD_CHECK='Both';
      NO_IO_CHECK='Both';
      NO_ASSERT_CHECK='TRUE';
      NO_DIR_CHECK='TRUE';
      ALLOW_CONNECT='TRUE';
    'PERN5':
      PIN_NUMBER='(A33)';
      INPUT_LOAD='(-0.01,0.01)';
    'PERP5':
      PIN_NUMBER='(A34)';
      INPUT_LOAD='(-0.01,0.01)';
    'GND_A35':
      PIN_NUMBER='(A35)';
      PINUSE='POWER';
      NO_LOAD_CHECK='Both';
      NO_IO_CHECK='Both';
      NO_ASSERT_CHECK='TRUE';
      NO_DIR_CHECK='TRUE';
      ALLOW_CONNECT='TRUE';
    'PERN6':
      PIN_NUMBER='(A36)';
      INPUT_LOAD='(-0.01,0.01)';
    'PERP6':
      PIN_NUMBER='(A37)';
      INPUT_LOAD='(-0.01,0.01)';
    'GND_A38':
      PIN_NUMBER='(A38)';
      PINUSE='POWER';
      NO_LOAD_CHECK='Both';
      NO_IO_CHECK='Both';
      NO_ASSERT_CHECK='TRUE';
      NO_DIR_CHECK='TRUE';
      ALLOW_CONNECT='TRUE';
    'PERN7':
      PIN_NUMBER='(A39)';
      INPUT_LOAD='(-0.01,0.01)';
    'PERP7':
      PIN_NUMBER='(A40)';
      INPUT_LOAD='(-0.01,0.01)';
    'GND_A41':
      PIN_NUMBER='(A41)';
      PINUSE='POWER';
      NO_LOAD_CHECK='Both';
      NO_IO_CHECK='Both';
      NO_ASSERT_CHECK='TRUE';
      NO_DIR_CHECK='TRUE';
      ALLOW_CONNECT='TRUE';
    'PRSNTB1#':
      PIN_NUMBER='(A42)';
      INPUT_LOAD='(-0.01,0.01)';
    'GND_A43':
      PIN_NUMBER='(A43)';
      PINUSE='POWER';
      NO_LOAD_CHECK='Both';
      NO_IO_CHECK='Both';
      NO_ASSERT_CHECK='TRUE';
      NO_DIR_CHECK='TRUE';
      ALLOW_CONNECT='TRUE';
    'PERN8':
      PIN_NUMBER='(A44)';
      INPUT_LOAD='(-0.01,0.01)';
    'PERP8':
      PIN_NUMBER='(A45)';
      INPUT_LOAD='(-0.01,0.01)';
    'GND_A46':
      PIN_NUMBER='(A46)';
      PINUSE='POWER';
      NO_LOAD_CHECK='Both';
      NO_IO_CHECK='Both';
      NO_ASSERT_CHECK='TRUE';
      NO_DIR_CHECK='TRUE';
      ALLOW_CONNECT='TRUE';
    'PERN9':
      PIN_NUMBER='(A47)';
      INPUT_LOAD='(-0.01,0.01)';
    'PERP9':
      PIN_NUMBER='(A48)';
      INPUT_LOAD='(-0.01,0.01)';
    'GND_A49':
      PIN_NUMBER='(A49)';
      PINUSE='POWER';
      NO_LOAD_CHECK='Both';
      NO_IO_CHECK='Both';
      NO_ASSERT_CHECK='TRUE';
      NO_DIR_CHECK='TRUE';
      ALLOW_CONNECT='TRUE';
    'PERN10':
      PIN_NUMBER='(A50)';
      INPUT_LOAD='(-0.01,0.01)';
    'PERP10':
      PIN_NUMBER='(A51)';
      INPUT_LOAD='(-0.01,0.01)';
    'GND_A52':
      PIN_NUMBER='(A52)';
      PINUSE='POWER';
      NO_LOAD_CHECK='Both';
      NO_IO_CHECK='Both';
      NO_ASSERT_CHECK='TRUE';
      NO_DIR_CHECK='TRUE';
      ALLOW_CONNECT='TRUE';
    'PERN11':
      PIN_NUMBER='(A53)';
      INPUT_LOAD='(-0.01,0.01)';
    'PERP11':
      PIN_NUMBER='(A54)';
      INPUT_LOAD='(-0.01,0.01)';
    'GND_A55':
      PIN_NUMBER='(A55)';
      PINUSE='POWER';
      NO_LOAD_CHECK='Both';
      NO_IO_CHECK='Both';
      NO_ASSERT_CHECK='TRUE';
      NO_DIR_CHECK='TRUE';
      ALLOW_CONNECT='TRUE';
    'PERN12':
      PIN_NUMBER='(A56)';
      INPUT_LOAD='(-0.01,0.01)';
    'PERP12':
      PIN_NUMBER='(A57)';
      INPUT_LOAD='(-0.01,0.01)';
    'GND_A58':
      PIN_NUMBER='(A58)';
      PINUSE='POWER';
      NO_LOAD_CHECK='Both';
      NO_IO_CHECK='Both';
      NO_ASSERT_CHECK='TRUE';
      NO_DIR_CHECK='TRUE';
      ALLOW_CONNECT='TRUE';
    'PERN13':
      PIN_NUMBER='(A59)';
      INPUT_LOAD='(-0.01,0.01)';
    'PERP13':
      PIN_NUMBER='(A60)';
      INPUT_LOAD='(-0.01,0.01)';
    'GND_A61':
      PIN_NUMBER='(A61)';
      PINUSE='POWER';
      NO_LOAD_CHECK='Both';
      NO_IO_CHECK='Both';
      NO_ASSERT_CHECK='TRUE';
      NO_DIR_CHECK='TRUE';
      ALLOW_CONNECT='TRUE';
    'PERN14':
      PIN_NUMBER='(A62)';
      INPUT_LOAD='(-0.01,0.01)';
    'PERP14':
      PIN_NUMBER='(A63)';
      INPUT_LOAD='(-0.01,0.01)';
    'GND_A64':
      PIN_NUMBER='(A64)';
      PINUSE='POWER';
      NO_LOAD_CHECK='Both';
      NO_IO_CHECK='Both';
      NO_ASSERT_CHECK='TRUE';
      NO_DIR_CHECK='TRUE';
      ALLOW_CONNECT='TRUE';
    'PERN15':
      PIN_NUMBER='(A65)';
      INPUT_LOAD='(-0.01,0.01)';
    'PERP15':
      PIN_NUMBER='(A66)';
      INPUT_LOAD='(-0.01,0.01)';
    'GND_A67':
      PIN_NUMBER='(A67)';
      PINUSE='POWER';
      NO_LOAD_CHECK='Both';
      NO_IO_CHECK='Both';
      NO_ASSERT_CHECK='TRUE';
      NO_DIR_CHECK='TRUE';
      ALLOW_CONNECT='TRUE';
    'USB_DATN':
      PIN_NUMBER='(A68)';
      BIDIRECTIONAL='TRUE';
      INPUT_LOAD='(-0.01,0.01)';
      OUTPUT_LOAD='(1.0,-1.0)';
    'USB_DATP':
      PIN_NUMBER='(A69)';
      BIDIRECTIONAL='TRUE';
      INPUT_LOAD='(-0.01,0.01)';
      OUTPUT_LOAD='(1.0,-1.0)';
    'PWRBRK0#':
      PIN_NUMBER='(A70)';
      BIDIRECTIONAL='TRUE';
      INPUT_LOAD='(-0.01,0.01)';
      OUTPUT_LOAD='(1.0,-1.0)';
    'PETP12':
      PIN_NUMBER='(B57)';
      OUTPUT_LOAD='(1.0,-1.0)';
    'GND_B58':
      PIN_NUMBER='(B58)';
      PINUSE='POWER';
      NO_LOAD_CHECK='Both';
      NO_IO_CHECK='Both';
      NO_ASSERT_CHECK='TRUE';
      NO_DIR_CHECK='TRUE';
      ALLOW_CONNECT='TRUE';
    'PETN13':
      PIN_NUMBER='(B59)';
      OUTPUT_LOAD='(1.0,-1.0)';
    'PETP13':
      PIN_NUMBER='(B60)';
      OUTPUT_LOAD='(1.0,-1.0)';
    'GND_B61':
      PIN_NUMBER='(B61)';
      PINUSE='POWER';
      NO_LOAD_CHECK='Both';
      NO_IO_CHECK='Both';
      NO_ASSERT_CHECK='TRUE';
      NO_DIR_CHECK='TRUE';
      ALLOW_CONNECT='TRUE';
    'PETN14':
      PIN_NUMBER='(B62)';
      OUTPUT_LOAD='(1.0,-1.0)';
    'PETP14':
      PIN_NUMBER='(B63)';
      OUTPUT_LOAD='(1.0,-1.0)';
    'GND_B64':
      PIN_NUMBER='(B64)';
      PINUSE='POWER';
      NO_LOAD_CHECK='Both';
      NO_IO_CHECK='Both';
      NO_ASSERT_CHECK='TRUE';
      NO_DIR_CHECK='TRUE';
      ALLOW_CONNECT='TRUE';
    'PETN15':
      PIN_NUMBER='(B65)';
      OUTPUT_LOAD='(1.0,-1.0)';
    'PETP15':
      PIN_NUMBER='(B66)';
      OUTPUT_LOAD='(1.0,-1.0)';
    'GND_B67':
      PIN_NUMBER='(B67)';
      PINUSE='POWER';
      NO_LOAD_CHECK='Both';
      NO_IO_CHECK='Both';
      NO_ASSERT_CHECK='TRUE';
      NO_DIR_CHECK='TRUE';
      ALLOW_CONNECT='TRUE';
    'RFU1_NC_B68':
      PIN_NUMBER='(B68)';
      OUTPUT_TYPE='(TS,TS)';
      INPUT_LOAD='(-0.01,0.01)';
      OUTPUT_LOAD='(1.0,-1.0)';
    'RFU1_NC_B69':
      PIN_NUMBER='(B69)';
      OUTPUT_TYPE='(TS,TS)';
      INPUT_LOAD='(-0.01,0.01)';
      OUTPUT_LOAD='(1.0,-1.0)';
    'PRSNTB3#':
      PIN_NUMBER='(B70)';
      INPUT_LOAD='(-0.01,0.01)';
    'G1':
      PIN_NUMBER='(G1)';
      PINUSE='POWER';
      NO_LOAD_CHECK='Both';
      NO_IO_CHECK='Both';
      NO_ASSERT_CHECK='TRUE';
      NO_DIR_CHECK='TRUE';
      ALLOW_CONNECT='TRUE';
    'G2':
      PIN_NUMBER='(G2)';
      PINUSE='POWER';
      NO_LOAD_CHECK='Both';
      NO_IO_CHECK='Both';
      NO_ASSERT_CHECK='TRUE';
      NO_DIR_CHECK='TRUE';
      ALLOW_CONNECT='TRUE';
    'G3':
      PIN_NUMBER='(G3)';
      PINUSE='POWER';
      NO_LOAD_CHECK='Both';
      NO_IO_CHECK='Both';
      NO_ASSERT_CHECK='TRUE';
      NO_DIR_CHECK='TRUE';
      ALLOW_CONNECT='TRUE';
    'G4':
      PIN_NUMBER='(G4)';
      PINUSE='POWER';
      NO_LOAD_CHECK='Both';
      NO_IO_CHECK='Both';
      NO_ASSERT_CHECK='TRUE';
      NO_DIR_CHECK='TRUE';
      ALLOW_CONNECT='TRUE';
    'G5':
      PIN_NUMBER='(G5)';
      PINUSE='POWER';
      NO_LOAD_CHECK='Both';
      NO_IO_CHECK='Both';
      NO_ASSERT_CHECK='TRUE';
      NO_DIR_CHECK='TRUE';
      ALLOW_CONNECT='TRUE';
  end_pin;
  body
    PART_NAME='SCONN168_ME1016810202011';
    BODY_NAME='SCONN168_ME1016810202011';
    PHYS_DES_PREFIX='J';
    CLASS='IO';
    NC_PINS='(H1,H2)';
  end_body;
end_primitive;

END.
